FILE_TYPE = MULTI_PHYS_TABLE;

PART 'SCHOTTKY_AC'

{========================================================================================}
:VALUE             | PART_TYPE | MATERIAL | PART_NUMBER       = STANDARD        | LIFECYCLE      | PART_NUMBER       | JEDEC_TYPE                 | DESCRIPTION                                | MANUFTR | MANUF_PN          | RD_CMPLS_LVL | CMPLS_LVL | CLASS | DIP_SMD | FP_ECN            | FROM_PJ          | DATA                                  | EE_CHECK_LIST | PSL | PREFERENCE | CREATOR | CREATEDAY  | STATUS ;
{========================================================================================}
 '60V/51.70A'      | 'SMLF'    | 'IC'     | 'BC0MDJ60Z00'(!)  = ''              | ''             | 'BC0MDJ60Z00'     |'D2723_SMCXC'| 'DIODE SMD 5.0SMDJ60A(60V,51.70A)'         | 'LFI'   | '5.0SMDJ60A'      | 'EP(V1)'     | 'EP(V1)'  | 'IC'  | ''      | ''                | 'T2L-CHEESE'     | '5-0SMD SERIES.pdf'                   | ''            | ''  | ''         | ''      | '20120131' | ''    
 '60V/51.70A'      | 'SMLF'    | 'EMPTY'  | 'BC0MDJ60Z00'(!)  = ''              | ''             | 'BC0MDJ60Z00'     |'D2723_SMCXC'| 'DIODE SMD 5.0SMDJ60A(60V,51.70A)'         | 'LFI'   | '5.0SMDJ60A'      | 'EP(V1)'     | 'EP(V1)'  | 'IC'  | ''      | ''                | 'T2L-CHEESE'     | '5-0SMD SERIES.pdf'                   | ''            | ''  | ''         | ''      | '20120131' | ''    
 'B380-13-F'       | 'SMLF'    | 'IC'     | 'BC00B380Z00'(!)  = ''              | ''             | 'BC00B380Z00'     |'D2723_SMCXD'| 'DIODE SMD B380-13-F(80V,100A,SCHOTTKY)'   | 'DDS'   | 'B380-13-F'       | 'EP(V1)'     | ''        | 'IC'  | ''      | ''                | 'T2L-CHEESE'     | 'DDS_B380B.pdf'                       | ''            | ''  | ''         | ''      | '20120207' | ''    
 'B380-13-F'       | 'SMLF'    | 'EMPTY'  | 'BC00B380Z00'(!)  = ''              | ''             | 'BC00B380Z00'     |'D2723_SMCXD'| 'DIODE SMD B380-13-F(80V,100A,SCHOTTKY)'   | 'DDS'   | 'B380-13-F'       | 'EP(V1)'     | ''        | 'IC'  | ''      | ''                | 'T2L-CHEESE'     | 'DDS_B380B.pdf'                       | ''            | ''  | ''         | ''      | '20120207' | ''    
 'MMSZ5230B'       | 'SMLF'    | 'IC'     | 'BD005230Z00'(!)  = ''              | ''             | 'BD005230Z00'     |'SOD123XD'| 'DIOIDE ZENER SMD MMSZ5230B(4.7V,SOD123)'  | 'PJT'   | 'MMSZ5230B'       | 'EU(V1)'     | ''        | 'IC'  | ''      | ''                | 'T2L-KC'         | 'MMSZ5245B-series.pdf'                | ''            | ''  | ''         | ''      | '20120329' | ''    
 'MMSZ5230B'       | 'SMLF'    | 'EMPTY'  | 'BD005230Z00'(!)  = ''              | ''             | 'BD005230Z00'     |'SOD123XD'| 'DIOIDE ZENER SMD MMSZ5230B(4.7V,SOD123)'  | 'PJT'   | 'MMSZ5230B'       | 'EU(V1)'     | ''        | 'IC'  | ''      | ''                | 'T2L-KC'         | 'MMSZ5245B-series.pdf'                | ''            | ''  | ''         | ''      | '20120329' | ''    
 'VS-30BQ040TRPBF' | 'SMLF'    | 'IC'     | 'BC30BQ04Z00'(!)  = 'End of Design' | 'End of Life'  | 'BC30BQ04Z00'     |'D2723_SMCXE_EOL'| 'DIODE SMD VS-30BQ040TRPBF(40V,3A)SMC'     | 'SIL'   | 'VS-30BQ040TRPBF' | 'EU(V1)'     | 'EU(V1)'  | 'IC'  | ''      | ''                | 'S2B-YU-LIN'     | 'SIL_VS-30BQ040TRPBF.pdf'             | ''            | ''  | ''         | ''      | '20120904' | ''    
 'VS-30BQ040TRPBF' | 'SMLF'    | 'EMPTY'  | 'BC30BQ04Z00'(!)  = 'End of Design' | 'End of Life'  | 'BC30BQ04Z00'     |'D2723_SMCXE_EOL'| 'DIODE SMD VS-30BQ040TRPBF(40V,3A)SMC'     | 'SIL'   | 'VS-30BQ040TRPBF' | 'EU(V1)'     | 'EU(V1)'  | 'IC'  | ''      | ''                | 'S2B-YU-LIN'     | 'SIL_VS-30BQ040TRPBF.pdf'             | ''            | ''  | ''         | ''      | '20120904' | ''    
 'SS0530'          | 'SMLF'    | 'IC'     | 'BCSS0530Z00'(!)  = ''              | ''             | 'BCSS0530Z00'     |'SOD123XD'| 'DIODE SMD SS0530(30V,0.5A)SOD-123'        | 'PJT'   | 'SS0530'          | 'EP(V1)'     | ''        | 'IC'  | ''      | ''                | 'S1D-OZ'         | 'PJT_SS0520-SS0540.pdf'               | ''            | ''  | ''         | ''      | '20120915' | ''    
 'SS0530'          | 'SMLF'    | 'EMPTY'  | 'BCSS0530Z00'(!)  = ''              | ''             | 'BCSS0530Z00'     |'SOD123XD'| 'DIODE SMD SS0530(30V,0.5A)SOD-123'        | 'PJT'   | 'SS0530'          | 'EP(V1)'     | ''        | 'IC'  | ''      | ''                | 'S1D-OZ'         | 'PJT_SS0520-SS0540.pdf'               | ''            | ''  | ''         | ''      | '20120915' | ''    
 'MBR0530T1G'      | 'SMLF'    | 'IC'     | 'BC000530Z33'(!)  = 'End of Design' | 'Comp-Approve' | 'BC000530Z33'     |'SOD123XE'| 'DIODE SCHOTTKY MBR0530T1G(SOD-123)'       | 'ONS'   | 'MBR0530T1G'      | 'EU(V1)'     | 'EU(V1)'  | 'IC'  | ''      | ''                | 'F03B-MARK'      | 'ONS_MBR0530T1-MBR0530T3.pdf'         | ''            | ''  | ''         | ''      | '20121114' | ''    
 'MBR0530T1G'      | 'SMLF'    | 'EMPTY'  | 'BC000530Z33'(!)  = 'End of Design' | 'Comp-Approve' | 'BC000530Z33'     |'SOD123XE'| 'DIODE SCHOTTKY MBR0530T1G(SOD-123)'       | 'ONS'   | 'MBR0530T1G'      | 'EU(V1)'     | 'EU(V1)'  | 'IC'  | ''      | ''                | 'F03B-MARK'      | 'ONS_MBR0530T1-MBR0530T3.pdf'         | ''            | ''  | ''         | ''      | '20121114' | ''    
 '100V/0.2A'       | 'SMLF'    | 'IC'     | 'BCBAT41KZ00'(!)  = 'End of Design' | 'Comp-Approve' | 'BCBAT41KZ00'     |'SOD523XB'| 'DIODE SMD BAT41KFILM(100V,0.2A,SCHOTTKY)' | 'SGT'   | 'BAT41KFILM'      | 'EP(V1)'     | ''        | 'IC'  | ''      | ''                | 'UH3-JOSH'       | 'SGT_BAT41.pdf'                       | ''            | ''  | ''         | ''      | '20120531' | ''    
 '100V/0.2A'       | 'SMLF'    | 'EMPTY'  | 'BCBAT41KZ00'(!)  = 'End of Design' | 'Comp-Approve' | 'BCBAT41KZ00'     |'SOD523XB'| 'DIODE SMD BAT41KFILM(100V,0.2A,SCHOTTKY)' | 'SGT'   | 'BAT41KFILM'      | 'EP(V1)'     | ''        | 'IC'  | ''      | ''                | 'UH3-JOSH'       | 'SGT_BAT41.pdf'                       | ''            | ''  | ''         | ''      | '20120531' | ''    
 'SBM54'           | 'SMLF'    | 'IC'     | 'BC0SBM54Z13'(!)  = 'End of Design' | 'End of Life'  | 'BC0SBM54Z13'     |'D2114_EOL'| 'DIODE SMD SBM54PT(40V.5A)SCHOTTKY'        | 'CNK'   | 'SBM54PT'         | ''           | 'EP'      | 'IC'  | ''      | ''                | 'S07'            | 'CNK_SBM54PT.pdf'                     | ''            | ''  | ''         | ''      | '20100726' | ''    
 'SBM54'           | 'SMLF'    | 'EMPTY'  | 'BC0SBM54Z13'(!)  = 'End of Design' | 'End of Life'  | 'BC0SBM54Z13'     |'D2114_EOL'| 'DIODE SMD SBM54PT(40V.5A)SCHOTTKY'        | 'CNK'   | 'SBM54PT'         | ''           | 'EP'      | 'IC'  | ''      | ''                | 'S07'            | 'CNK_SBM54PT.pdf'                     | ''            | ''  | ''         | ''      | '20100726' | ''    
 'BAT54T1G'        | 'SMLF'    | 'IC'     | 'BCBAT54TZ03'(!)  = ''              | ''             | 'BCBAT54TZ03'     |'SOD123XE'| 'DIODE SMD BAT54T1G(30V,0.2A,SOD-123)'     | 'ONS'   | 'BAT54T1G'        | 'EP(V1)'     | ''        | 'IC'  | ''      | ''                | 'T2H-ALAN'       | 'ONS_BAT54T1G.pdf'                    | ''            | ''  | ''         | ''      | '20121203' | ''    
 'BAT54T1G'        | 'SMLF'    | 'EMPTY'  | 'BCBAT54TZ03'(!)  = ''              | ''             | 'BCBAT54TZ03'     |'SOD123XE'| 'DIODE SMD BAT54T1G(30V,0.2A,SOD-123)'     | 'ONS'   | 'BAT54T1G'        | 'EP(V1)'     | ''        | 'IC'  | ''      | ''                | 'T2H-ALAN'       | 'ONS_BAT54T1G.pdf'                    | ''            | ''  | ''         | ''      | '20121203' | ''    
 'MBRS130LT3G'     | 'SMLF'    | 'IC'     | 'BC000130ZD3'(!)  = 'End of Design' | 'Comp-Approve' | 'BC000130ZD3'     |'D2114'| 'DIODE SMD MBRS130LT3G(30V 1A SBD)'        | 'ONS'   | 'MBRS130LT3G'     | ''           | 'EU'      | 'IC'  | ''      | ''                | 'S75-LA'         | 'MBRS130LT3G.pdf'                     | ''            | ''  | ''         | ''      | '20130108' | ''    
 'MBRS130LT3G'     | 'SMLF'    | 'EMPTY'  | 'BC000130ZD3'(!)  = 'End of Design' | 'Comp-Approve' | 'BC000130ZD3'     |'D2114'| 'DIODE SMD MBRS130LT3G(30V 1A SBD)'        | 'ONS'   | 'MBRS130LT3G'     | ''           | 'EU'      | 'IC'  | ''      | ''                | 'S75-LA'         | 'MBRS130LT3G.pdf'                     | ''            | ''  | ''         | ''      | '20130108' | ''    
 'SMBJ13A-13-F'    | 'SMLF'    | 'IC'     | 'BC0MBJ13Z01'(!)  = ''              | ''             | 'BC0MBJ13Z01'     |'D2114A'| 'DIODE SMD SMBJ13A-13-F(13V, 27.9A)'       | 'DDS'   | 'SMBJ13A-13-F'    | 'EU(V1)'     | ''        | 'IC'  | ''      | ''                | 'S1MS-CHEESE'    | 'DDS_SMBJ5(C)A-SMBJ170(C)A.pdf'       | ''            | ''  | ''         | ''      | '20130319' | ''    
 'SMBJ13A-13-F'    | 'SMLF'    | 'EMPTY'  | 'BC0MBJ13Z01'(!)  = ''              | ''             | 'BC0MBJ13Z01'     |'D2114A'| 'DIODE SMD SMBJ13A-13-F(13V, 27.9A)'       | 'DDS'   | 'SMBJ13A-13-F'    | 'EU(V1)'     | ''        | 'IC'  | ''      | ''                | 'S1MS-CHEESE'    | 'DDS_SMBJ5(C)A-SMBJ170(C)A.pdf'       | ''            | ''  | ''         | ''      | '20130319' | ''    
 'SMBJ13A'         | 'SMLF'    | 'IC'     | 'BC0MBJ13Z00'(!)  = ''              | ''             | 'BC0MBJ13Z00'     |'D2114XB'| 'DIODE SMD SMBJ13A(13V,600W)DO-214AA'      | 'LFI'   | 'SMBJ13A'         | 'EP(V1)'     | 'EP(V1)'  | 'IC'  | ''      | ''                | 'JBF-MEALY'      | 'LFI_SMBJ-SERIES.pdf'                 | ''            | ''  | ''         | ''      | '20130403' | ''    
 'SMBJ13A'         | 'SMLF'    | 'EMPTY'  | 'BC0MBJ13Z00'(!)  = ''              | ''             | 'BC0MBJ13Z00'     |'D2114XB'| 'DIODE SMD SMBJ13A(13V,600W)DO-214AA'      | 'LFI'   | 'SMBJ13A'         | 'EP(V1)'     | 'EP(V1)'  | 'IC'  | ''      | ''                | 'JBF-MEALY'      | 'LFI_SMBJ-SERIES.pdf'                 | ''            | ''  | ''         | ''      | '20130403' | ''    
 'PMEG2005AEL'     | 'SMLF'    | 'IC'     | 'BC2005AEZ00'(!)  = ''              | ''             | 'BC2005AEZ00'     |'SOD882'| 'DIODE PMEG2005AEL(20V,0.5A)(SOD882)'      | 'NXP'   | 'PMEG2005AEL'     | 'EP(V1)'     | 'EP(V1)'  | 'IC'  | ''      | ''                | 'S2S-BENJAMIN'   | 'NXP_PMEG2005AEL.pdf'                 | ''            | ''  | ''         | ''      | '20130514' | ''    
 'PMEG2005AEL'     | 'SMLF'    | 'EMPTY'  | 'BC2005AEZ00'(!)  = ''              | ''             | 'BC2005AEZ00'     |'SOD882'| 'DIODE PMEG2005AEL(20V,0.5A)(SOD882)'      | 'NXP'   | 'PMEG2005AEL'     | 'EP(V1)'     | 'EP(V1)'  | 'IC'  | ''      | ''                | 'S2S-BENJAMIN'   | 'NXP_PMEG2005AEL.pdf'                 | ''            | ''  | ''         | ''      | '20130514' | ''    
 'SX33L'           | 'SMLF'    | 'IC'     | 'BC0SX33LZ00'(!)  = ''              | ''             | 'BC0SX33LZ00'     |'D2010XH'| 'DIODE SMD SX33L(30V,3A,SCHOTTKY,SMA)'     | 'PJT'   | 'SX33L'           | 'EU(V1)'     | 'EU(V1)'  | 'IC'  | ''      | ''                | 'S2MF-VINCENT'   | 'PJT_SX33L.pdf'                       | ''            | ''  | ''         | ''      | '20130719' | ''    
 'SX33L'           | 'SMLF'    | 'EMPTY'  | 'BC0SX33LZ00'(!)  = ''              | ''             | 'BC0SX33LZ00'     |'D2010XH'| 'DIODE SMD SX33L(30V,3A,SCHOTTKY,SMA)'     | 'PJT'   | 'SX33L'           | 'EU(V1)'     | 'EU(V1)'  | 'IC'  | ''      | ''                | 'S2MF-VINCENT'   | 'PJT_SX33L.pdf'                       | ''            | ''  | ''         | ''      | '20130719' | ''    
 'SMCJ60(C)A-13-F' | 'SMLF'    | 'IC'     | 'BCSMCJ60Z00'(!)  = ''              | ''             | 'BCSMCJ60Z00'     |'D2723_SMCXD'| 'DIODE SMD SMCJ60(C)A-13-F(60V,1500W,SMC)' | 'DDS'   | 'SMCJ60(C)A-13-F' | 'EP(V1)'     | ''        | 'IC'  | ''      | ''                | 'MF1R-DENNY'     | 'SMCJ5-0-C-A_SMCJ170-C-A_REV18-2.pdf' | ''            | ''  | ''         | ''      | '20140207' | ''    
 'SMCJ60(C)A-13-F' | 'SMLF'    | 'EMPTY'  | 'BCSMCJ60Z00'(!)  = ''              | ''             | 'BCSMCJ60Z00'     |'D2723_SMCXD'| 'DIODE SMD SMCJ60(C)A-13-F(60V,1500W,SMC)' | 'DDS'   | 'SMCJ60(C)A-13-F' | 'EP(V1)'     | ''        | 'IC'  | ''      | ''                | 'MF1R-DENNY'     | 'SMCJ5-0-C-A_SMCJ170-C-A_REV18-2.pdf' | ''            | ''  | ''         | ''      | '20140207' | ''    
 'RB720M-30'       | 'SMLF'    | 'IC'     | 'BC720M30Z00'(!)  = ''              | ''             | 'BC720M30Z00'     |'SOD923'| 'DIODE SMD RB720M-30(30V,0.1A,SCHOTTKY)'   | 'PJT'   | 'RB720M-30'       | 'EP(V1)'     | ''        | 'IC'  | ''      | ''                | 'T2H-GAVEN'      | 'PJT_RB720M-30_REV0.2.pdf'            | ''            | ''  | ''         | ''      | '20140813' | ''    
 'RB720M-30'       | 'SMLF'    | 'EMPTY'  | 'BC720M30Z00'(!)  = ''              | ''             | 'BC720M30Z00'     |'SOD923'| 'DIODE SMD RB720M-30(30V,0.1A,SCHOTTKY)'   | 'PJT'   | 'RB720M-30'       | 'EP(V1)'     | ''        | 'IC'  | ''      | ''                | 'T2H-GAVEN'      | 'PJT_RB720M-30_REV0.2.pdf'            | ''            | ''  | ''         | ''      | '20140813' | ''    
 'B130LB-13-F'     | 'SMLF'    | 'IC'     | 'BC000130ZE1'(!)  = 'End of Design' | 'Comp-Approve' | 'BC000130ZE1'     |'D2114XA'| 'DIODE B130LB-13-F(30V 1A SHTKY,SMB)'      | 'DDS'   | 'B130LB-13-F'     | 'EU'         | 'EU'      | 'IC'  | ''      | ''                | 'T6MG-MARK'      | 'DDS_B130LB-13-F_REV11-2.pdf'         | ''            | ''  | ''         | ''      | '20141211' | ''    
 'B130LB-13-F'     | 'SMLF'    | 'EMPTY'  | 'BC000130ZE1'(!)  = 'End of Design' | 'Comp-Approve' | 'BC000130ZE1'     |'D2114XA'| 'DIODE B130LB-13-F(30V 1A SHTKY,SMB)'      | 'DDS'   | 'B130LB-13-F'     | 'EU'         | 'EU'      | 'IC'  | ''      | ''                | 'T6MG-MARK'      | 'DDS_B130LB-13-F_REV11-2.pdf'         | ''            | ''  | ''         | ''      | '20141211' | ''    
 'B260-13-F'       | 'SMLF'    | 'IC'     | 'BC000260Z02'(!)  = ''              | ''             | 'BC000260Z02'     |'D2114XA'| 'DIODE SMB B260-13-F(60V,2.0A)'            | 'DDS'   | 'B260-13-F'       | 'EP(V1)'     | 'EP(V1)'  | 'IC'  | ''      | ''                | 'T2H-GAVEN'      | 'DDS_B260-13-F.pdf'                   | ''            | ''  | ''         | ''      | '20150325' | ''    
 'B260-13-F'       | 'SMLF'    | 'EMPTY'  | 'BC000260Z02'(!)  = ''              | ''             | 'BC000260Z02'     |'D2114XA'| 'DIODE SMB B260-13-F(60V,2.0A)'            | 'DDS'   | 'B260-13-F'       | 'EP(V1)'     | 'EP(V1)'  | 'IC'  | ''      | ''                | 'T2H-GAVEN'      | 'DDS_B260-13-F.pdf'                   | ''            | ''  | ''         | ''      | '20150325' | ''    
 'B3100-13-F'      | 'SMLF'    | 'IC'     | 'BC310013Z00'(!)  = ''              | ''             | 'BC310013Z00'     |'D2723_SMCXD'| 'DIODE SMD B3100-13-F (100V,3A)SCHOTKY'    | 'DDS'   | 'B3100-13-F'      | 'EP(V1)'     | ''        | 'IC'  | ''      | ''                | 'T2R-AARON'      | 'DDS_B370-B3100_REV14-2.pdf'          | ''            | ''  | ''         | ''      | '20150327' | ''    
 'B3100-13-F'      | 'SMLF'    | 'EMPTY'  | 'BC310013Z00'(!)  = ''              | ''             | 'BC310013Z00'     |'D2723_SMCXD'| 'DIODE SMD B3100-13-F (100V,3A)SCHOTKY'    | 'DDS'   | 'B3100-13-F'      | 'EP(V1)'     | ''        | 'IC'  | ''      | ''                | 'T2R-AARON'      | 'DDS_B370-B3100_REV14-2.pdf'          | ''            | ''  | ''         | ''      | '20150327' | ''    
 'B340B-13-F'      | 'SMLF'    | 'IC'     | 'BC0B340BZ15'(!)  = ''              | ''             | 'BC0B340BZ15'     |'D2114A'| 'DIODE B340B-13-F(40V.3A)SMD'              | 'DDS'   | 'B340B-13-F'      | ''           | 'EP'      | 'IC'  | ''      | ''                | 'JSA-MEALY'      | 'B340B-13-F.pdf'                      | ''            | ''  | ''         | ''      | '20150904' | ''    
 'B340B-13-F'      | 'SMLF'    | 'EMPTY'  | 'BC0B340BZ15'(!)  = ''              | ''             | 'BC0B340BZ15'     |'D2114A'| 'DIODE B340B-13-F(40V.3A)SMD'              | 'DDS'   | 'B340B-13-F'      | ''           | 'EP'      | 'IC'  | ''      | ''                | 'JSA-MEALY'      | 'B340B-13-F.pdf'                      | ''            | ''  | ''         | ''      | '20150904' | ''    
 'B340A-13-F'      | 'SMLF'    | 'IC'     | 'BC000340Z30'(!)  = ''              | ''             | 'BC000340Z30'     |'D2010XF'| 'DIODE SMD B340A-13-F(40V,3A)SCHOTTKY'     | 'DDS'   | 'B340A-13-F'      | 'EP(V1)'     | 'EP(V1)'  | 'IC'  | ''      | ''                | 'S5B-ROSSI'      | 'DDS_B340A-13-F.pdf'                  | ''            | ''  | ''         | ''      | '20151231' | ''    
 'B340A-13-F'      | 'SMLF'    | 'EMPTY'  | 'BC000340Z30'(!)  = ''              | ''             | 'BC000340Z30'     |'D2010XF'| 'DIODE SMD B340A-13-F(40V,3A)SCHOTTKY'     | 'DDS'   | 'B340A-13-F'      | 'EP(V1)'     | 'EP(V1)'  | 'IC'  | ''      | ''                | 'S5B-ROSSI'      | 'DDS_B340A-13-F.pdf'                  | ''            | ''  | ''         | ''      | '20151231' | ''    
 'RB161SS-20T2R'   | 'SMLF'    | 'IC'     | 'BC0161SS000'(!)  = 'End of Design' | 'Comp-Approve' | 'BC0161SS000'     |'D0603_RB161SS-20T2R'| 'DIODE SMD RB161SS-20T2R(30V,1A)SCHOTTKY'  | 'ROH'   | 'RB161SS-20T2R'   | 'EP(V1)'     | ''        | 'IC'  | ''      | ''                | 'F06-SHERRY'     | 'ROH_RB161SS-20T2R.pdf'               | ''            | ''  | ''         | ''      | '20160308' | ''    
 'RB161SS-20T2R'   | 'SMLF'    | 'EMPTY'  | 'BC0161SS000'(!)  = 'End of Design' | 'Comp-Approve' | 'BC0161SS000'     |'D0603_RB161SS-20T2R'| 'DIODE SMD RB161SS-20T2R(30V,1A)SCHOTTKY'  | 'ROH'   | 'RB161SS-20T2R'   | 'EP(V1)'     | ''        | 'IC'  | ''      | ''                | 'F06-SHERRY'     | 'ROH_RB161SS-20T2R.pdf'               | ''            | ''  | ''         | ''      | '20160308' | ''    
 'RB520S30'        | 'SMLF'    | 'IC'     | 'BC520S30Z01'(!)  = ''              | ''             | 'BC520S30Z01'     |'SOD523_1-2X0-8'| 'DIODE SMD RB520S30(30V,200MA)'            | 'NXP'   | 'RB520S30'        | 'EP(V1)'     | ''        | 'IC'  | ''      | ''                | 'QS8204-8i-SEAN' | 'NXP_RB520S30.pdf'                    | ''            | ''  | ''         | ''      | '20160804' | ''    
 'RB520S30'        | 'SMLF'    | 'EMPTY'  | 'BC520S30Z01'(!)  = ''              | ''             | 'BC520S30Z01'     |'SOD523_1-2X0-8'| 'DIODE SMD RB520S30(30V,200MA)'            | 'NXP'   | 'RB520S30'        | 'EP(V1)'     | ''        | 'IC'  | ''      | ''                | 'QS8204-8i-SEAN' | 'NXP_RB520S30.pdf'                    | ''            | ''  | ''         | ''      | '20160804' | ''    
 'RB161M-20TR'     | 'SMLF'    | 'IC'     | 'BC161M20Z06'(!)  = ''              | ''             | 'BC161M20Z06'     |'SOD123_2-6X1-6'| 'DIODE SMD RB161M-20TR(20V,1A,SCHOTTY)'    | 'ROH'   | 'RB161M-20TR'     | 'EP'         | 'EP(V1)'  | 'IC'  | ''      | ''                | 'UH3M-KEVIN'     | 'ROH_RB161M-20TR_JUN-30-2009.pdf'     | ''            | ''  | ''         | ''      | '20160809' | ''    
 'RB161M-20TR'     | 'SMLF'    | 'EMPTY'  | 'BC161M20Z06'(!)  = ''              | ''             | 'BC161M20Z06'     |'SOD123_2-6X1-6'| 'DIODE SMD RB161M-20TR(20V,1A,SCHOTTY)'    | 'ROH'   | 'RB161M-20TR'     | 'EP'         | 'EP(V1)'  | 'IC'  | ''      | ''                | 'UH3M-KEVIN'     | 'ROH_RB161M-20TR_JUN-30-2009.pdf'     | ''            | ''  | ''         | ''      | '20160809' | ''    
 'RB161MM-20TR'    | 'SMLF'    | 'IC'     | 'BC000161Z00'(!)  = ''              | ''             | 'BC000161Z00'     |'SOD123_2-6X1-6'| 'DIODE SMD RB161MM-20TR(20V,1A,SCHOTTY)'   | 'ROH'   | 'RB161MM-20TR'    | 'EU(V1)'     | ''        | 'IC'  | ''      | ''                | 'UH3M-KEVIN'     | 'ROH_RB161MM-20TR_revA_201408.pdf'    | ''            | ''  | ''         | ''      | '20160818' | ''    
 'RB161MM-20TR'    | 'SMLF'    | 'EMPTY'  | 'BC000161Z00'(!)  = ''              | ''             | 'BC000161Z00'     |'SOD123_2-6X1-6'| 'DIODE SMD RB161MM-20TR(20V,1A,SCHOTTY)'   | 'ROH'   | 'RB161MM-20TR'    | 'EU(V1)'     | ''        | 'IC'  | ''      | ''                | 'UH3M-KEVIN'     | 'ROH_RB161MM-20TR_revA_201408.pdf'    | ''            | ''  | ''         | ''      | '20160818' | ''    
 'MB310'           | 'SMLF'    | 'IC'     | 'BC000310000'(!)  = ''              | ''             | 'BC000310000'     |'D2723_SMCXG'| 'DIODE SMD MB310(100V,3A)SCHOTTKY'         | 'PJT'   | 'MB310'           | 'EP(V1)'     | ''        | 'IC'  | ''      | ''                | 'T2H-HSUEHYEN'   | 'PJT_MB34_SERIESRE_V6-13-2016.pdf'    | ''            | ''  | ''         | ''      | '20161220' | ''    
 'MB310'           | 'SMLF'    | 'EMPTY'  | 'BC000310000'(!)  = ''              | ''             | 'BC000310000'     |'D2723_SMCXG'| 'DIODE SMD MB310(100V,3A)SCHOTTKY'         | 'PJT'   | 'MB310'           | 'EP(V1)'     | ''        | 'IC'  | ''      | ''                | 'T2H-HSUEHYEN'   | 'PJT_MB34_SERIESRE_V6-13-2016.pdf'    | ''            | ''  | ''         | ''      | '20161220' | ''    
 'MBRS3100T3G'     | 'SMLF'    | 'IC'     | 'BC003100Z00'(!)  = ''              | ''             | 'BC003100Z00'     |'D2723_SMCXJ'| 'DIODE SMD MBRS3100T3G(100V,3A)AEC'        | 'ONS'   | 'MBRS3100T3G'     | 'EP(V1)'     | ''        | 'IC'  | ''      | ''                | 'T2H-HSUEH-YEN'  | 'ONS_MBRS3100T3G.pdf'                 | ''            | ''  | ''         | ''      | '20161228' | ''    
 'MBRS3100T3G'     | 'SMLF'    | 'EMPTY'  | 'BC003100Z00'(!)  = ''              | ''             | 'BC003100Z00'     |'D2723_SMCXJ'| 'DIODE SMD MBRS3100T3G(100V,3A)AEC'        | 'ONS'   | 'MBRS3100T3G'     | 'EP(V1)'     | ''        | 'IC'  | ''      | ''                | 'T2H-HSUEH-YEN'  | 'ONS_MBRS3100T3G.pdf'                 | ''            | ''  | ''         | ''      | '20161228' | ''    
 'S310'            | 'SMLF'    | 'IC'     | 'BC000310001'(!)  = ''              | ''             | 'BC000310001'     |'D2723_SMCXI'| 'DIODE SMD S310(100V,3A,2.27W)SCHOTTKY'    | 'FAC'   | 'S310'            | 'EP(V1)'     | ''        | 'IC'  | ''      | ''                | 'T2H-HSUEH-YEN'  | 'FAC_S310.pdf'                        | ''            | ''  | ''         | ''      | '20161228' | ''    
 'S310'            | 'SMLF'    | 'EMPTY'  | 'BC000310001'(!)  = ''              | ''             | 'BC000310001'     |'D2723_SMCXI'| 'DIODE SMD S310(100V,3A,2.27W)SCHOTTKY'    | 'FAC'   | 'S310'            | 'EP(V1)'     | ''        | 'IC'  | ''      | ''                | 'T2H-HSUEH-YEN'  | 'FAC_S310.pdf'                        | ''            | ''  | ''         | ''      | '20161228' | ''    
 'B140HW-7'        | 'SMLF'    | 'IC'     | 'BC000140Z05'(!)  = 'End of Design' | 'Comp-Approve' | 'BC000140Z05'     |'SOD123_2-7X1-55XA'| 'DIODE SMD B140HW-7(40V,1A)SCHOTTKY'       | 'DDS'   | 'B140HW-7'        | 'EP(V1)'     | 'EP(V1)'  | 'IC'  | ''      | ''                | 'JBE-STAN'       | 'DDS_B140HW-7.pdf'                    | ''            | ''  | ''         | ''      | '20170126' | ''    
 'B140HW-7'        | 'SMLF'    | 'EMPTY'  | 'BC000140Z05'(!)  = 'End of Design' | 'Comp-Approve' | 'BC000140Z05'     |'SOD123_2-7X1-55XA'| 'DIODE SMD B140HW-7(40V,1A)SCHOTTKY'       | 'DDS'   | 'B140HW-7'        | 'EP(V1)'     | 'EP(V1)'  | 'IC'  | ''      | ''                | 'JBE-STAN'       | 'DDS_B140HW-7.pdf'                    | ''            | ''  | ''         | ''      | '20170126' | ''    
 'SS1040'          | 'SMLF'    | 'IC'     | 'BCSS1040005'(!)  = ''              | ''             | 'BCSS1040005'     |'SOD123_2-65X1-6'| 'DIODE SMD SS1040(40V,1A,SCHOTTKY)'        | 'PJT'   | 'SS1040'          | 'EP(V1)'     | 'EP(V1)'  | 'IC'  | ''      | ''                | 'JBE-STAN'       | 'PJT_SS1040.pdf'                      | ''            | ''  | ''         | ''      | '20170202' | ''    
 'SS1040'          | 'SMLF'    | 'EMPTY'  | 'BCSS1040005'(!)  = ''              | ''             | 'BCSS1040005'     |'SOD123_2-65X1-6'| 'DIODE SMD SS1040(40V,1A,SCHOTTKY)'        | 'PJT'   | 'SS1040'          | 'EP(V1)'     | 'EP(V1)'  | 'IC'  | ''      | ''                | 'JBE-STAN'       | 'PJT_SS1040.pdf'                      | ''            | ''  | ''         | ''      | '20170202' | ''    
 'RB551V30 T/R13'  | 'SMLF'    | 'IC'     | 'BCRB551VZ00'(!)  = ''              | ''             | 'BCRB551VZ00'     |'SOD323XD'| 'DIODE SMD RB551V30 T/R(30V,500MA,SOD323)' | 'PJT'   | 'RB551V30 T/R13'  | 'EP(V1)'     | 'EP(V1)'  | 'IC'  | ''      | ''                | 'CAVIUM-MARCUS'  | 'PJT_RB551V30TR13.pdf'                | ''            | ''  | ''         | ''      | '20170329' | ''    
 'RB551V30 T/R13'  | 'SMLF'    | 'EMPTY'  | 'BCRB551VZ00'(!)  = ''              | ''             | 'BCRB551VZ00'     |'SOD323XD'| 'DIODE SMD RB551V30 T/R(30V,500MA,SOD323)' | 'PJT'   | 'RB551V30 T/R13'  | 'EP(V1)'     | 'EP(V1)'  | 'IC'  | ''      | ''                | 'CAVIUM-MARCUS'  | 'PJT_RB551V30TR13.pdf'                | ''            | ''  | ''         | ''      | '20170329' | ''    
 'NSR20406NXT5G'   | 'SMLF'    | 'IC'     | 'BC020406Z00'(!)  = ''              | 'End of Life'  | 'BC020406Z00'     |'D_DSN2_0603_EOL'| 'DIODE SMD NSR20406NXT5G(40V,2A)SCHOTTKY'  | 'ONS'   | 'NSR20406NXT5G'   | 'EP(V1)'     | ''        | 'IC'  | ''      | ''                | 'T2N-HSUEH-YEN'  | 'ONS_NSR20406NXT5G.pdf'               | ''            | ''  | ''         | ''      | '20170705' | ''    
 'NSR20406NXT5G'   | 'SMLF'    | 'EMPTY'  | 'BC020406Z00'(!)  = ''              | 'End of Life'  | 'BC020406Z00'     |'D_DSN2_0603_EOL'| 'DIODE SMD NSR20406NXT5G(40V,2A)SCHOTTKY'  | 'ONS'   | 'NSR20406NXT5G'   | 'EP(V1)'     | ''        | 'IC'  | ''      | ''                | 'T2N-HSUEH-YEN'  | 'ONS_NSR20406NXT5G.pdf'               | ''            | ''  | ''         | ''      | '20170705' | ''    
 'NRVB1H100SFT3G'  | 'SMLF'    | 'IC'     | 'BC100SFTZ00'(!)  = ''              | ''             | 'BC100SFTZ00'     |'SOD123XF'| 'DIODE SMD NRVB1H100S(100V,50A,SOD-123FL)' | 'ONS'   | 'NRVB1H100SFT3G'  | 'EP(V1)'     | 'EP(V1)'  | 'IC'  | ''      | ''                | 'T2N-JANE'       | 'MBR1H100SFT3G_NRVB1H100SFT3G.pdf'    | ''            | ''  | ''         | ''      | '20170817' | ''    
 'NRVB1H100SFT3G'  | 'SMLF'    | 'EMPTY'  | 'BC100SFTZ00'(!)  = ''              | ''             | 'BC100SFTZ00'     |'SOD123XF'| 'DIODE SMD NRVB1H100S(100V,50A,SOD-123FL)' | 'ONS'   | 'NRVB1H100SFT3G'  | 'EP(V1)'     | 'EP(V1)'  | 'IC'  | ''      | ''                | 'T2N-JANE'       | 'MBR1H100SFT3G_NRVB1H100SFT3G.pdf'    | ''            | ''  | ''         | ''      | '20170817' | ''    
 'SBR2U30SA'       | 'SMLF'    | 'IC'     | 'BC2U30SAZ00'(!)  = ''              | ''             | 'BC2U30SAZ00'     |'D2010XF'| 'DIODE SMD SBR2U30SA(30V,2A,SCHOTTKY,SMA)' | 'DDS'   | 'SBR2U30SA-13'    | 'EP(V1)'     | ''        | 'IC'  | ''      | ''                | 'S2LR-YIMIN'     | 'DDS_SBR2U30SA.pdf'                   | ''            | ''  | ''         | ''      | '20170919' | ''    
 'SBR2U30SA'       | 'SMLF'    | 'EMPTY'  | 'BC2U30SAZ00'(!)  = ''              | ''             | 'BC2U30SAZ00'     |'D2010XF'| 'DIODE SMD SBR2U30SA(30V,2A,SCHOTTKY,SMA)' | 'DDS'   | 'SBR2U30SA-13'    | 'EP(V1)'     | ''        | 'IC'  | ''      | ''                | 'S2LR-YIMIN'     | 'DDS_SBR2U30SA.pdf'                   | ''            | ''  | ''         | ''      | '20170919' | ''    
 'RB521S30'        | 'SMLF'    | 'IC'     | 'BC521S30Z00'(!)  = ''              | ''             | 'BC521S30Z00'     |'SOD523_1-2X0-8XB'| 'DIODE SCHOTTKY RB521S30(30V,0.2A)'        | 'PJT'   | 'RB521S30'        | 'EP(V1)'     | 'EP(V1)'  | 'IC'  | ''      | ''                | 'F09-SEAN'       | 'PJT_RB521S30.pdf'                    | ''            | ''  | ''         | ''      | '20170921' | ''    
 'RB521S30'        | 'SMLF'    | 'EMPTY'  | 'BC521S30Z00'(!)  = ''              | ''             | 'BC521S30Z00'     |'SOD523_1-2X0-8XB'| 'DIODE SCHOTTKY RB521S30(30V,0.2A)'        | 'PJT'   | 'RB521S30'        | 'EP(V1)'     | 'EP(V1)'  | 'IC'  | ''      | ''                | 'F09-SEAN'       | 'PJT_RB521S30.pdf'                    | ''            | ''  | ''         | ''      | '20170921' | ''    
 'BAT54HT1G'       | 'SMLF'    | 'IC'     | 'BC54HT1GZ00'(!)  = ''              | ''             | 'BC54HT1GZ00'     |'SOD323XK'| 'DIODE SMD BAT54HT1G(30V,0.2A,S0D323)'     | 'FAC'   | 'BAT54HT1G'       | 'EP(V1)'     | 'EP(V1)'  | 'IC'  | ''      | ''                | 'T2HV-EASON'     | 'FAC_BAT54HT1G.pdf'                   | ''            | ''  | ''         | ''      | '20161220' | ''    
 'BAT54HT1G'       | 'SMLF'    | 'EMPTY'  | 'BC54HT1GZ00'(!)  = ''              | ''             | 'BC54HT1GZ00'     |'SOD323XK'| 'DIODE SMD BAT54HT1G(30V,0.2A,S0D323)'     | 'FAC'   | 'BAT54HT1G'       | 'EP(V1)'     | 'EP(V1)'  | 'IC'  | ''      | ''                | 'T2HV-EASON'     | 'FAC_BAT54HT1G.pdf'                   | ''            | ''  | ''         | ''      | '20161220' | ''    
 'MBR130T1G'       | 'SMLF'    | 'IC'     | 'BCMBR130Z00'(!)  = ''              | ''             | 'BCMBR130Z00'     |'SOD123XE'| 'DIODE SMD MBR130T1G(30V,1A,SCHOTTKY)'     | 'ONS'   | 'MBR130T1G'       | 'EP(V1)'     | ''        | 'IC'  | ''      | ''                | 'T2N-MARK'       | 'ONS_MBR130T1G.pdf'                   | ''            | ''  | ''         | ''      | '20171027' | ''    
 'MBR130T1G'       | 'SMLF'    | 'EMPTY'  | 'BCMBR130Z00'(!)  = ''              | ''             | 'BCMBR130Z00'     |'SOD123XE'| 'DIODE SMD MBR130T1G(30V,1A,SCHOTTKY)'     | 'ONS'   | 'MBR130T1G'       | 'EP(V1)'     | ''        | 'IC'  | ''      | ''                | 'T2N-MARK'       | 'ONS_MBR130T1G.pdf'                   | ''            | ''  | ''         | ''      | '20171027' | ''    
 'RB521S30FN2'     | 'SMLF'    | 'IC'     | 'BCRB521SZ00'(!)  = ''              | ''             | 'BCRB521SZ00'     |'D0402_RB521S30FN2'| 'DIODE SMD RB521S30FN2(30V,0.2A,SCHOTTKY)' | 'PJT'   | 'RB521S30FN2'     | 'EP(V1)'     | ''        | 'IC'  | ''      | ''                | 'S5G-JUSTIN'     | 'PJT_RB521S30FN2.pdf'                 | ''            | ''  | ''         | ''      | '20180226' | ''    
 'RB521S30FN2'     | 'SMLF'    | 'EMPTY'  | 'BCRB521SZ00'(!)  = ''              | ''             | 'BCRB521SZ00'     |'D0402_RB521S30FN2'| 'DIODE SMD RB521S30FN2(30V,0.2A,SCHOTTKY)' | 'PJT'   | 'RB521S30FN2'     | 'EP(V1)'     | ''        | 'IC'  | ''      | ''                | 'S5G-JUSTIN'     | 'PJT_RB521S30FN2.pdf'                 | ''            | ''  | ''         | ''      | '20180226' | ''    
 'RB521CM-30T2R'   | 'SMLF'    | 'IC'     | 'BCRB521CZ01'(!)  = ''              | ''             | 'BCRB521CZ01'     |'SOD923_0-86X0-6'| 'DIODESMD RB521CM-30T2R(30V,0.1A,SCHOTTKY' | 'ROH'   | 'RB521CM-30T2R'   | 'EP(V1)'     | 'EP(V1)'  | 'IC'  | ''      | ''                | 'S5G-JUSTIN'     | 'ROH_RB521CM-30T2R.pdf'               | ''            | ''  | ''         | ''      | '20180227' | ''    
 'RB521CM-30T2R'   | 'SMLF'    | 'EMPTY'  | 'BCRB521CZ01'(!)  = ''              | ''             | 'BCRB521CZ01'     |'SOD923_0-86X0-6'| 'DIODESMD RB521CM-30T2R(30V,0.1A,SCHOTTKY' | 'ROH'   | 'RB521CM-30T2R'   | 'EP(V1)'     | 'EP(V1)'  | 'IC'  | ''      | ''                | 'S5G-JUSTIN'     | 'ROH_RB521CM-30T2R.pdf'               | ''            | ''  | ''         | ''      | '20180227' | ''    
 'BAS3010S-02LRH'  | 'SMLF'    | 'IC'     | 'BC3010SZ000'(!)  = ''              | ''             | 'BC3010SZ000'     |'D0402_BAS3010S-02LRH'| 'DIODE SMD BAS3010S-02LRH(30V,1A)'         | 'SNI'   | 'BAS3010S-02LRH'  | 'EP(V1)'     | ''        | 'IC'  | ''      | ''                | 'T2N-CARLOS'     | 'SNI_BAS3010S-02LRH.pdf'              | ''            | ''  | ''         | ''      | '20180329' | ''    
 'BAS3010S-02LRH'  | 'SMLF'    | 'EMPTY'  | 'BC3010SZ000'(!)  = ''              | ''             | 'BC3010SZ000'     |'D0402_BAS3010S-02LRH'| 'DIODE SMD BAS3010S-02LRH(30V,1A)'         | 'SNI'   | 'BAS3010S-02LRH'  | 'EP(V1)'     | ''        | 'IC'  | ''      | ''                | 'T2N-CARLOS'     | 'SNI_BAS3010S-02LRH.pdf'              | ''            | ''  | ''         | ''      | '20180329' | ''    
 'PMEG4002ELD'     | 'SMLF'    | 'IC'     | 'BC4002ELZ00'(!)  = ''              | ''             | 'BC4002ELZ00'     |'SOD882D'| 'DIODE PMEG4002ELD(40V,0.2A)(SOD882D)'     | 'NXP'   | 'PMEG4002ELD'     | 'EP(V1)'     | 'EP(V1)'  | 'IC'  | ''      | ''                | 'S1F-STANLEY'    | 'NXP_PMEG4002ELD_Rev 1.pdf'           | ''            | ''  | ''         | ''      | '20130923' | ''    
 'PMEG4002ELD'     | 'SMLF'    | 'EMPTY'  | 'BC4002ELZ00'(!)  = ''              | ''             | 'BC4002ELZ00'     |'SOD882D'| 'DIODE PMEG4002ELD(40V,0.2A)(SOD882D)'     | 'NXP'   | 'PMEG4002ELD'     | 'EP(V1)'     | 'EP(V1)'  | 'IC'  | ''      | ''                | 'S1F-STANLEY'    | 'NXP_PMEG4002ELD_Rev 1.pdf'           | ''            | ''  | ''         | ''      | '20130923' | ''    
 '5.0SMDJ12A'      | 'SMLF'    | 'IC'     | 'BCMDJ12AZ00'(!)  = ''              | ''             | 'BCMDJ12AZ00'     |'D_SMDJ60A'| 'DIODE SMD 5.0SMDJ12A(12V,252A,5000W)'     | 'LFI'   | '5.0SMDJ12A'      | 'EP(V1)'     | ''        | 'IC'  | ''      | ''                | 'T6U-JACK'       | 'LFI_5.0SMDJ12A.pdf'                  | ''            | ''  | ''         | ''      | '20180717' | ''    
 '5.0SMDJ12A'      | 'SMLF'    | 'EMPTY'  | 'BCMDJ12AZ00'(!)  = ''              | ''             | 'BCMDJ12AZ00'     |'D_SMDJ60A'| 'DIODE SMD 5.0SMDJ12A(12V,252A,5000W)'     | 'LFI'   | '5.0SMDJ12A'      | 'EP(V1)'     | ''        | 'IC'  | ''      | ''                | 'T6U-JACK'       | 'LFI_5.0SMDJ12A.pdf'                  | ''            | ''  | ''         | ''      | '20180717' | ''    
 'PMEG2005EL'      | 'SMLF'    | 'IC'     | 'BC2005ELZ00'(!)  = ''              | ''             | 'BC2005ELZ00'     |'SOD882_0-985X0-585'| 'DIODE PMEG2005EL(20V,0.5A)(SOD882)'       | 'NXP'   | 'PMEG2005EL'      | 'EP(V1)'     | 'EP(V1)'  | 'IC'  | ''      | ''                | 'JB4-JOHNNY'     | 'NXP_PMEG2005EL.pdf'                  | ''            | ''  | ''         | ''      | '20180723' | ''    
 'PMEG2005EL'      | 'SMLF'    | 'EMPTY'  | 'BC2005ELZ00'(!)  = ''              | ''             | 'BC2005ELZ00'     |'SOD882_0-985X0-585'| 'DIODE PMEG2005EL(20V,0.5A)(SOD882)'       | 'NXP'   | 'PMEG2005EL'      | 'EP(V1)'     | 'EP(V1)'  | 'IC'  | ''      | ''                | 'JB4-JOHNNY'     | 'NXP_PMEG2005EL.pdf'                  | ''            | ''  | ''         | ''      | '20180723' | ''    
 'DSF01S30SL'      | 'SMLF'    | 'IC'     | 'BC1S30SLZ00'(!)  = ''              | ''             | 'BC1S30SLZ00'     |'SOD962_0-62X0-32'| 'DIODE SMD DSF01S30SL(30V,0.1A,SCHOTTKY)'  | 'TOS'   | 'DSF01S30SL'      | 'EP(V1)'     | ''        | 'IC'  | ''      | ''                | 'F0B-HANK'       | 'TOS_DSF01S30SL.pdf'                  | ''            | ''  | ''         | ''      | '20180822' | ''    
 'DSF01S30SL'      | 'SMLF'    | 'EMPTY'  | 'BC1S30SLZ00'(!)  = ''              | ''             | 'BC1S30SLZ00'     |'SOD962_0-62X0-32'| 'DIODE SMD DSF01S30SL(30V,0.1A,SCHOTTKY)'  | 'TOS'   | 'DSF01S30SL'      | 'EP(V1)'     | ''        | 'IC'  | ''      | ''                | 'F0B-HANK'       | 'TOS_DSF01S30SL.pdf'                  | ''            | ''  | ''         | ''      | '20180822' | ''    
 'BZT52C4V7LP-7'   | 'SMLF'    | 'IC'     | 'BD52C4V7Z00'(!)  = ''              | ''             | 'BD52C4V7Z00'     |'D0402XA'| 'DIODE ZENER BZT52C4V7LP-7(4.7V,0.25W)'    | 'DDS'   | 'BZT52C4V7LP-7'   | 'EP(V1)'     | ''        | 'IC'  | ''      | ''                | 'S5U-JOANNE'     | 'DDS_BZT52C4V7LP-7.pdf'               | ''            | ''  | ''         | ''      | '20181217' | ''    
 'BZT52C4V7LP-7'   | 'SMLF'    | 'EMPTY'  | 'BD52C4V7Z00'(!)  = ''              | ''             | 'BD52C4V7Z00'     |'D0402XA'| 'DIODE ZENER BZT52C4V7LP-7(4.7V,0.25W)'    | 'DDS'   | 'BZT52C4V7LP-7'   | 'EP(V1)'     | ''        | 'IC'  | ''      | ''                | 'S5U-JOANNE'     | 'DDS_BZT52C4V7LP-7.pdf'               | ''            | ''  | ''         | ''      | '20181217' | ''    
 'BAS70-02L'       | 'SMLF'    | 'IC'     | 'BC0BAS70Z15'(!)  = ''              | ''             | 'BC0BAS70Z15'     |'D0402_BAS3010S-02LRH_H20'| 'DIODE SMD BAS70-02L(70V,0.07A,0.25W)'     | 'SNI'   | 'BAS70-02L'       | 'EP(V1)'     | 'EP(V1)'  | 'IC'  | ''      | ''                | 'T2N-CHEER'      | 'SNI_BAS70-02L.pdf'                   | ''            | ''  | ''         | ''      | '20190403' | ''    
 'BAS70-02L'       | 'SMLF'    | 'EMPTY'  | 'BC0BAS70Z15'(!)  = ''              | ''             | 'BC0BAS70Z15'     |'D0402_BAS3010S-02LRH_H20'| 'DIODE SMD BAS70-02L(70V,0.07A,0.25W)'     | 'SNI'   | 'BAS70-02L'       | 'EP(V1)'     | 'EP(V1)'  | 'IC'  | ''      | ''                | 'T2N-CHEER'      | 'SNI_BAS70-02L.pdf'                   | ''            | ''  | ''         | ''      | '20190403' | ''    
 'MMSD701T1G'      | 'SMLF'    | 'IC'     | 'BAM701T0000'(!)  = ''              | 'End of Life'  | 'BAM701T0000'     |'SOD123XE_EOL'| 'TRANS MOS MMSD701T1G(70V,0.2A,0,225W)'    | 'ONS'   | 'MMSD701T1G'      | 'EP(V1)'     | ''        | 'IC'  | ''      | ''                | 'T2N-JW'         | 'ONS_MMSD701T1G.pdf'                  | ''            | ''  | ''         | ''      | '20190417' | ''    
 'MMSD701T1G'      | 'SMLF'    | 'EMPTY'  | 'BAM701T0000'(!)  = ''              | 'End of Life'  | 'BAM701T0000'     |'SOD123XE_EOL'| 'TRANS MOS MMSD701T1G(70V,0.2A,0,225W)'    | 'ONS'   | 'MMSD701T1G'      | 'EP(V1)'     | ''        | 'IC'  | ''      | ''                | 'T2N-JW'         | 'ONS_MMSD701T1G.pdf'                  | ''            | ''  | ''         | ''      | '20190417' | ''    
 'P4SMAJ13A'       | 'SMLF'    | 'IC'     | 'BCMAJ13AZ03'(!)  = ''              | ''             | 'BCMAJ13AZ03'     |'D2010XH'| 'DIODE SMD P4SMAJ13A (400W,13V)'           | 'PJT'   | 'P4SMAJ13A'       | 'EP(V1)'     | 'EP(V1)'  | 'IC'  | ''      | ''                | 'F0C-ABER'       | 'PJT_P4SMAJ13A.pdf'                   | ''            | ''  | ''         | ''      | '20190521' | ''    
 'P4SMAJ13A'       | 'SMLF'    | 'EMPTY'  | 'BCMAJ13AZ03'(!)  = ''              | ''             | 'BCMAJ13AZ03'     |'D2010XH'| 'DIODE SMD P4SMAJ13A (400W,13V)'           | 'PJT'   | 'P4SMAJ13A'       | 'EP(V1)'     | 'EP(V1)'  | 'IC'  | ''      | ''                | 'F0C-ABER'       | 'PJT_P4SMAJ13A.pdf'                   | ''            | ''  | ''         | ''      | '20190521' | ''    
 'PMEG4002EL'      | 'SMLF'    | 'IC'     | 'BC4002ELZ01'(!)  = ''              | ''             | 'BC4002ELZ01'     |'SOD882_0-985X0-585'| 'DIODE PMEG4002EL (40V,0.2A) (SOD882)'     | 'NXP'   | 'PMEG4002EL'      | 'EP(V1)'     | ''        | 'IC'  | ''      | ''                | 'T2C-CARLOS'     | 'NXP_PMEG4002EL.pdf'                  | ''            | ''  | ''         | ''      | '20190603' | ''    
 'PMEG4002EL'      | 'SMLF'    | 'EMPTY'  | 'BC4002ELZ01'(!)  = ''              | ''             | 'BC4002ELZ01'     |'SOD882_0-985X0-585'| 'DIODE PMEG4002EL (40V,0.2A) (SOD882)'     | 'NXP'   | 'PMEG4002EL'      | 'EP(V1)'     | ''        | 'IC'  | ''      | ''                | 'T2C-CARLOS'     | 'NXP_PMEG4002EL.pdf'                  | ''            | ''  | ''         | ''      | '20190603' | ''    
 'SDM2U40CSP-7B'   | 'SMLF'    | 'IC'     | 'BCU40CSPU02'(!)  = ''              | ''             | 'BCU40CSPU02'     |'D_X3-WLB1608-2'| 'DIODE SMD SDM2U40CSP-7B (40V,2A)'         | 'DDS'   | 'SDM2U40CSP-7B'   | 'EP(V1)'     | 'EP(V1)'  | 'IC'  | ''      | ''                | 'F0G-EGBERT'     | 'DDS_SDM2U40CSP-7B.pdf'               | ''            | ''  | ''         | ''      | '20190820' | ''    
 'SDM2U40CSP-7B'   | 'SMLF'    | 'EMPTY'  | 'BCU40CSPU02'(!)  = ''              | ''             | 'BCU40CSPU02'     |'D_X3-WLB1608-2'| 'DIODE SMD SDM2U40CSP-7B (40V,2A)'         | 'DDS'   | 'SDM2U40CSP-7B'   | 'EP(V1)'     | 'EP(V1)'  | 'IC'  | ''      | ''                | 'F0G-EGBERT'     | 'DDS_SDM2U40CSP-7B.pdf'               | ''            | ''  | ''         | ''      | '20190820' | ''    
 'PMEG1020EA'      | 'SMLF'    | 'IC'     | 'BC1020EAZ00'(!)  = ''              | ''             | 'BC1020EAZ00'     |'SOD323F_H44'| 'DIODE SMD PMEG1020EA(10V,2A)AEC'          | 'NXP'   | 'PMEG1020EA'      | 'EU(V1)'     | ''        | 'IC'  | ''      | 'PMEG1020EA.msg'  | 'S8I-FRANK'      | 'NXP_PMEG1020EA.pdf'                  | ''            | ''  | ''         | ''      | '20191021' | ''    
 'PMEG1020EA'      | 'SMLF'    | 'EMPTY'  | 'BC1020EAZ00'(!)  = ''              | ''             | 'BC1020EAZ00'     |'SOD323F_H44'| 'DIODE SMD PMEG1020EA(10V,2A)AEC'          | 'NXP'   | 'PMEG1020EA'      | 'EU(V1)'     | ''        | 'IC'  | ''      | 'PMEG1020EA.msg'  | 'S8I-FRANK'      | 'NXP_PMEG1020EA.pdf'                  | ''            | ''  | ''         | ''      | '20191021' | ''    
 'BAT54WS'         | 'SMLF'    | 'IC'     | 'BCBAT54WZ09'(!)  = ''              | ''             | 'BCBAT54WZ09'     |'SOD323XD'| 'DIODE SMD BAT54WS(30V,0.2A,SCHOTTKY)'     | 'PJT'   | 'BAT54WS'         | 'EP(V1)'     | 'EP(V1)'  | 'IC'  | ''      | ''                | 'S5C-HOWARD'     | 'PJT_BAT54WS.pdf'                     | ''            | ''  | ''         | ''      | '20191125' | ''    
 'BAT54WS'         | 'SMLF'    | 'EMPTY'  | 'BCBAT54WZ09'(!)  = ''              | ''             | 'BCBAT54WZ09'     |'SOD323XD'| 'DIODE SMD BAT54WS(30V,0.2A,SCHOTTKY)'     | 'PJT'   | 'BAT54WS'         | 'EP(V1)'     | 'EP(V1)'  | 'IC'  | ''      | ''                | 'S5C-HOWARD'     | 'PJT_BAT54WS.pdf'                     | ''            | ''  | ''         | ''      | '20191125' | ''    
 'SX34F'           | 'SMLF'    | 'IC'     | 'BC00SX34Z01'(!)  = ''              | 'End of Life'  | 'BC00SX34Z01'     |'D1510_SMAF_EOL'| 'DIODE SMD SX34F(40V,3A,SCHOTTKY)'         | 'PJT'   | 'SX34F'           | 'EP(V1)'     | 'EP(V1)'  | 'IC'  | ''      | ''                | 'S9S-CHRIS'      | 'PJT_SX34F.pdf'                       | ''            | ''  | ''         | ''      | '20200303' | ''    
 'SX34F'           | 'SMLF'    | 'EMPTY'  | 'BC00SX34Z01'(!)  = ''              | 'End of Life'  | 'BC00SX34Z01'     |'D1510_SMAF_EOL'| 'DIODE SMD SX34F(40V,3A,SCHOTTKY)'         | 'PJT'   | 'SX34F'           | 'EP(V1)'     | 'EP(V1)'  | 'IC'  | ''      | ''                | 'S9S-CHRIS'      | 'PJT_SX34F.pdf'                       | ''            | ''  | ''         | ''      | '20200303' | ''    
 'MBRS540T3G'      | 'SMLF'    | 'IC'     | 'BC000540Z02'(!)  = ''              | ''             | 'BC000540Z02'     |'D2723_SMCXJ'| 'DIODE SCHOTTKY MBRS540T3G(40V,5A,SMC)'    | 'ONS'   | 'MBRS540T3G'      | 'EP'         | 'EP'      | 'IC'  | ''      | ''                | 'S8A-JAY'        | 'ONS_MBRS540T3G.pdf'                  | ''            | ''  | ''         | ''      | '20200304' | ''    
 'MBRS540T3G'      | 'SMLF'    | 'EMPTY'  | 'BC000540Z02'(!)  = ''              | ''             | 'BC000540Z02'     |'D2723_SMCXJ'| 'DIODE SCHOTTKY MBRS540T3G(40V,5A,SMC)'    | 'ONS'   | 'MBRS540T3G'      | 'EP'         | 'EP'      | 'IC'  | ''      | ''                | 'S8A-JAY'        | 'ONS_MBRS540T3G.pdf'                  | ''            | ''  | ''         | ''      | '20200304' | ''    
 'BAT760'          | 'SMLF'    | 'IC'     | 'BCBAT760007'(!)  = ''              | ''             | 'BCBAT760007'     |'SOD323F_H44'| 'DIODE SCHOTTKY BAT760(20V,SOD323)'        | 'PHI'   | 'BAT760'          | 'EP'         | 'EP'      | 'IC'  | ''      | 'BAT760.msg'      | 'S8A-KENNY'      | 'PHI_BAT760.pdf'                      | ''            | ''  | ''         | ''      | '20200309' | ''    
 'BAT760'          | 'SMLF'    | 'EMPTY'  | 'BCBAT760007'(!)  = ''              | ''             | 'BCBAT760007'     |'SOD323F_H44'| 'DIODE SCHOTTKY BAT760(20V,SOD323)'        | 'PHI'   | 'BAT760'          | 'EP'         | 'EP'      | 'IC'  | ''      | 'BAT760.msg'      | 'S8A-KENNY'      | 'PHI_BAT760.pdf'                      | ''            | ''  | ''         | ''      | '20200309' | ''    
 'BAT46WJ'         | 'SMLF'    | 'IC'     | 'BCBAT46WZ01'(!)  = ''              | ''             | 'BCBAT46WZ01'     |'SOD323F'| 'DIODE SMD BAT46WJ(100V,2.5A)AEC'          | 'NXE'   | 'BAT46WJ'         | 'EU(V1)'     | ''        | 'IC'  | ''      | ''                | 'S8A-KENNY'      | 'NXE_BAT46WJ.pdf'                     | ''            | ''  | ''         | ''      | '20200312' | ''    
 'BAT46WJ'         | 'SMLF'    | 'EMPTY'  | 'BCBAT46WZ01'(!)  = ''              | ''             | 'BCBAT46WZ01'     |'SOD323F'| 'DIODE SMD BAT46WJ(100V,2.5A)AEC'          | 'NXE'   | 'BAT46WJ'         | 'EU(V1)'     | ''        | 'IC'  | ''      | ''                | 'S8A-KENNY'      | 'NXE_BAT46WJ.pdf'                     | ''            | ''  | ''         | ''      | '20200312' | ''    
 'MBR1H100SFT3G'   | 'SMLF'    | 'IC'     | 'BC01H100000'(!)  = ''              | ''             | 'BC01H100000'     |'SOD123_2-7X1-65'| 'DIODE SMD MBR1H100SFT3G(100V,1A)'         | 'ONS'   | 'MBR1H100SFT3G'   | 'EP(V1)'     | 'EP(V1)'  | 'IC'  | ''      | ''                | 'S8A-YC'         | 'ONS_MBR1H100SFT3G.pdf'               | ''            | ''  | ''         | ''      | '20200406' | ''    
 'MBR1H100SFT3G'   | 'SMLF'    | 'EMPTY'  | 'BC01H100000'(!)  = ''              | ''             | 'BC01H100000'     |'SOD123_2-7X1-65'| 'DIODE SMD MBR1H100SFT3G(100V,1A)'         | 'ONS'   | 'MBR1H100SFT3G'   | 'EP(V1)'     | 'EP(V1)'  | 'IC'  | ''      | ''                | 'S8A-YC'         | 'ONS_MBR1H100SFT3G.pdf'               | ''            | ''  | ''         | ''      | '20200406' | ''    
 'B340-13-F'       | 'SMLF'    | 'IC'     | 'BC00B340Z00'(!)  = ''              | ''             | 'BC00B340Z00'     |'D2723_SMCXD'| 'DIODE SMD B340-13-F(40V,3A)'              | 'DDS'   | 'B340-13-F'       | 'EU(V1)'     | 'EU(V1)'  | 'IC'  | ''      | ''                | 'S3I-VINCENT'    | 'DDS_B340-13-F.pdf'                   | ''            | ''  | ''         | ''      | '20200620' | ''    
 'B340-13-F'       | 'SMLF'    | 'EMPTY'  | 'BC00B340Z00'(!)  = ''              | ''             | 'BC00B340Z00'     |'D2723_SMCXD'| 'DIODE SMD B340-13-F(40V,3A)'              | 'DDS'   | 'B340-13-F'       | 'EU(V1)'     | 'EU(V1)'  | 'IC'  | ''      | ''                | 'S3I-VINCENT'    | 'DDS_B340-13-F.pdf'                   | ''            | ''  | ''         | ''      | '20200620' | ''    
 'SDM161645EP3-7'  | 'SMLF'    | 'IC'     | 'BC161645Z00'(!)  = ''              | ''             | 'BC161645Z00'     |'D_X3-TSN1616-2_1-6X1-6'| 'DIODE SMD SDM161645EP3-7(45V,5A)SCHOTTKY' | 'DDS'   | 'SDM161645EP3-7'  | 'EP(V1)'     | ''        | 'IC'  | ''      | ''                | 'F0E-CHUN'       | 'DDS_SDM161645EP3-7.pdf'              | ''            | ''  | ''         | ''      | '20201106' | ''    
 'SDM161645EP3-7'  | 'SMLF'    | 'EMPTY'  | 'BC161645Z00'(!)  = ''              | ''             | 'BC161645Z00'     |'D_X3-TSN1616-2_1-6X1-6'| 'DIODE SMD SDM161645EP3-7(45V,5A)SCHOTTKY' | 'DDS'   | 'SDM161645EP3-7'  | 'EP(V1)'     | ''        | 'IC'  | ''      | ''                | 'F0E-CHUN'       | 'DDS_SDM161645EP3-7.pdf'              | ''            | ''  | ''         | ''      | '20201106' | ''    
 'SB34AFC'         | 'SMLF'    | 'IC'     | 'BC034AFCZ00'(!)  = ''              | ''             | 'BC034AFCZ00'     |'D1510_SMAF-C'| 'DIODE SMD SB34AFC(40V,3A,SCHOTTKY)'       | 'PJT'   | 'SB34AFC'         | 'EP(V1)'     | 'EP(V1)'  | 'IC'  | ''      | ''                | 'S9S-CHRIS'      | 'PJT_SB34AFC.pdf'                     | ''            | ''  | ''         | ''      | '20201125' | ''    
 'SB34AFC'         | 'SMLF'    | 'EMPTY'  | 'BC034AFCZ00'(!)  = ''              | ''             | 'BC034AFCZ00'     |'D1510_SMAF-C'| 'DIODE SMD SB34AFC(40V,3A,SCHOTTKY)'       | 'PJT'   | 'SB34AFC'         | 'EP(V1)'     | 'EP(V1)'  | 'IC'  | ''      | ''                | 'S9S-CHRIS'      | 'PJT_SB34AFC.pdf'                     | ''            | ''  | ''         | ''      | '20201125' | ''    
 'B520C-13-F'      | 'SMLF'    | 'IC'     | 'BC0B520CZ00'(!)  = ''              | ''             | 'BC0B520CZ00'     |'D2723_SMCXF'| 'DIODE SMD B520C-13-F(20V,5A,SMC)'         | 'DDS'   | 'B520C-13-F'      | 'EP'         | ''        | 'IC'  | ''      | ''                | 'S6YQ-SIMON'     | 'DDS_B520C-13-F.pdf'                  | ''            | ''  | ''         | ''      | '20201230' | ''    
 'B520C-13-F'      | 'SMLF'    | 'EMPTY'  | 'BC0B520CZ00'(!)  = ''              | ''             | 'BC0B520CZ00'     |'D2723_SMCXF'| 'DIODE SMD B520C-13-F(20V,5A,SMC)'         | 'DDS'   | 'B520C-13-F'      | 'EP'         | ''        | 'IC'  | ''      | ''                | 'S6YQ-SIMON'     | 'DDS_B520C-13-F.pdf'                  | ''            | ''  | ''         | ''      | '20201230' | ''    
 'RB751VM-40TE-17' | 'SMLF'    | 'IC'     | 'BCRB751VZ01'(!)  = ''              | ''             | 'BCRB751VZ01'     |'SOD323_1-7X1-25XA'| 'DIODE SMD RB751VM-40TE-17(40V,30MA)'      | 'ROH'   | 'RB751VM-40TE-17' | 'EP(V1)'     | 'EP(V1)'  | 'IC'  | ''      | ''                | 'T6G-JAY'        | 'ROH_RB751VM-40TE-17.pdf'             | ''            | ''  | ''         | ''      | '20210607' | ''    
 'RB751VM-40TE-17' | 'SMLF'    | 'EMPTY'  | 'BCRB751VZ01'(!)  = ''              | ''             | 'BCRB751VZ01'     |'SOD323_1-7X1-25XA'| 'DIODE SMD RB751VM-40TE-17(40V,30MA)'      | 'ROH'   | 'RB751VM-40TE-17' | 'EP(V1)'     | 'EP(V1)'  | 'IC'  | ''      | ''                | 'T6G-JAY'        | 'ROH_RB751VM-40TE-17.pdf'             | ''            | ''  | ''         | ''      | '20210607' | ''    
 'RSX101VYM30FHTR' | 'SMLF'    | 'IC'     | 'BC1VYM30Z00'(!)  = ''              | ''             | 'BC1VYM30Z00'     |'SOD323_2X1-4'| 'DIODE SMD RSX101VYM30FH(30V,1A)SCHOTTKY'  | 'ROH'   | 'RSX101VYM30FHTR' | 'EP(V1)'     | ''        | 'IC'  | ''      | ''                | 'F08-FENTUS'     | 'ROH_RSX101VYM30FHTR.pdf'             | ''            | ''  | ''         | ''      | '20210721' | ''    
 'RSX101VYM30FHTR' | 'SMLF'    | 'EMPTY'  | 'BC1VYM30Z00'(!)  = ''              | ''             | 'BC1VYM30Z00'     |'SOD323_2X1-4'| 'DIODE SMD RSX101VYM30FH(30V,1A)SCHOTTKY'  | 'ROH'   | 'RSX101VYM30FHTR' | 'EP(V1)'     | ''        | 'IC'  | ''      | ''                | 'F08-FENTUS'     | 'ROH_RSX101VYM30FHTR.pdf'             | ''            | ''  | ''         | ''      | '20210721' | ''    
 'CUS10S30'        | 'SMLF'    | 'IC'     | 'BCS10S30Z00'(!)  = ''              | ''             | 'BCS10S30Z00'     |'SOD323_1-7X1-25XB'| 'DIODE SMD SCHOTTKY  CUS10S30(30V,1A)'     | 'TOS'   | 'CUS10S30'        | 'EP(V1)'     | ''        | 'IC'  | ''      | ''                | 'A7M-ANDY'       | 'TOS_CUS10S30.pdf'                    | ''            | ''  | ''         | ''      | '20210805' | ''    
 'CUS10S30'        | 'SMLF'    | 'EMPTY'  | 'BCS10S30Z00'(!)  = ''              | ''             | 'BCS10S30Z00'     |'SOD323_1-7X1-25XB'| 'DIODE SMD SCHOTTKY  CUS10S30(30V,1A)'     | 'TOS'   | 'CUS10S30'        | 'EP(V1)'     | ''        | 'IC'  | ''      | ''                | 'A7M-ANDY'       | 'TOS_CUS10S30.pdf'                    | ''            | ''  | ''         | ''      | '20210805' | ''    
 'CUS10F30'        | 'SMLF'    | 'IC'     | 'BC0CUS10000'(!)  = 'End of Design' | 'Comp-Approve' | 'BC0CUS10000'     |'SOD323_1-7X1-25XB'| 'DIODE SMD SCHOTTKY  CUS10F30(30V,1A)'     | 'TOS'   | 'CUS10F30'        | 'EP(V1)'     | 'EP(V1)'  | 'IC'  | ''      | ''                | 'A7M-ANDY'       | 'TOS_CUS10F30.pdf'                    | ''            | ''  | ''         | ''      | '20210827' | ''    
 'CUS10F30'        | 'SMLF'    | 'EMPTY'  | 'BC0CUS10000'(!)  = 'End of Design' | 'Comp-Approve' | 'BC0CUS10000'     |'SOD323_1-7X1-25XB'| 'DIODE SMD SCHOTTKY  CUS10F30(30V,1A)'     | 'TOS'   | 'CUS10F30'        | 'EP(V1)'     | 'EP(V1)'  | 'IC'  | ''      | ''                | 'A7M-ANDY'       | 'TOS_CUS10F30.pdf'                    | ''            | ''  | ''         | ''      | '20210827' | ''    
 'PMEG4030ER'      | 'SMLF'    | 'IC'     | 'BC4030ERZ00'(!)  = ''              | ''             | 'BC4030ERZ00'     |'SOD123W_1-7X2-6XA'| 'DIODE PMEG4030ER(40V,3A)SOD123W AEC'      | 'NXP'   | 'PMEG4030ER'      | 'EP(V1)'     | 'EP(V1)'  | 'IC'  | ''      | ''                | 'S8Z-JACK'       | 'NXP_PMEG4030ER.pdf'                  | ''            | ''  | ''         | ''      | '20210930' | ''    
 'PMEG4030ER'      | 'SMLF'    | 'EMPTY'  | 'BC4030ERZ00'(!)  = ''              | ''             | 'BC4030ERZ00'     |'SOD123W_1-7X2-6XA'| 'DIODE PMEG4030ER(40V,3A)SOD123W AEC'      | 'NXP'   | 'PMEG4030ER'      | 'EP(V1)'     | 'EP(V1)'  | 'IC'  | ''      | ''                | 'S8Z-JACK'       | 'NXP_PMEG4030ER.pdf'                  | ''            | ''  | ''         | ''      | '20210930' | ''    
 'PMEG4005AEA'     | 'SMLF'    | 'IC'     | 'BC4005AEZ00'(!)  = ''              | ''             | 'BC4005AEZ00'     |'SOD323F_H44'| 'DIODE SMD PMEG4005AEA(40V,0.5A,SOD323)'   | 'NXP'   | 'PMEG4005AEA'     | 'EP(V1)'     | 'EP(V1)'  | 'IC'  | ''      | ''                | 'F0EG-RAY'       | 'NXP_PMEG4005AEA.pdf'                 | ''            | ''  | ''         | ''      | '20220314' | ''    
 'PMEG4005AEA'     | 'SMLF'    | 'EMPTY'  | 'BC4005AEZ00'(!)  = ''              | ''             | 'BC4005AEZ00'     |'SOD323F_H44'| 'DIODE SMD PMEG4005AEA(40V,0.5A,SOD323)'   | 'NXP'   | 'PMEG4005AEA'     | 'EP(V1)'     | 'EP(V1)'  | 'IC'  | ''      | ''                | 'F0EG-RAY'       | 'NXP_PMEG4005AEA.pdf'                 | ''            | ''  | ''         | ''      | '20220314' | ''    
 'SS0520'          | 'SMLF'    | 'IC'     | 'BCSS0520Z00'(!)  = ''              | ''             | 'BCSS0520Z00'     |'SOD123XD'| 'DIODE SMD SS0520(40V, 0.5A)SOD-123'       | 'PJT'   | 'SS0520'          | 'EP(V1)'     | 'EP(V1)'  | 'IC'  | ''      | ''                | 'F06D-DUNCAN'    | 'PJT_SS0520-SS0540.pdf'               | ''            | ''  | ''         | ''      | '20220325' | ''    
 'SS0520'          | 'SMLF'    | 'EMPTY'  | 'BCSS0520Z00'(!)  = ''              | ''             | 'BCSS0520Z00'     |'SOD123XD'| 'DIODE SMD SS0520(40V, 0.5A)SOD-123'       | 'PJT'   | 'SS0520'          | 'EP(V1)'     | 'EP(V1)'  | 'IC'  | ''      | ''                | 'F06D-DUNCAN'    | 'PJT_SS0520-SS0540.pdf'               | ''            | ''  | ''         | ''      | '20220325' | ''    
 'NSR0130P2T5G'    | 'SMLF'    | 'IC'     | 'BC000130Z05'(!)  = ''              | ''             | 'BC000130Z05'     |'SOD923'| 'DIODE SMD NSR0130P2T5G(30V,0.1A,SOD-923)' | 'ONS'   | 'NSR0130P2T5G'    | 'EP(V1)'     | 'EP(V1)'  | 'IC'  | ''      | ''                | 'MF6-YAN'        | 'ONS_NSR0130P2T5G.pdf'                | ''            | ''  | ''         | ''      | '20220610' | ''    
 'NSR0130P2T5G'    | 'SMLF'    | 'EMPTY'  | 'BC000130Z05'(!)  = ''              | ''             | 'BC000130Z05'     |'SOD923'| 'DIODE SMD NSR0130P2T5G(30V,0.1A,SOD-923)' | 'ONS'   | 'NSR0130P2T5G'    | 'EP(V1)'     | 'EP(V1)'  | 'IC'  | ''      | ''                | 'MF6-YAN'        | 'ONS_NSR0130P2T5G.pdf'                | ''            | ''  | ''         | ''      | '20220610' | ''    
 'SSA34-M3/61T'    | 'SMLF'    | 'IC'     | 'BC0SSA34Z00'(!)  = ''              | ''             | 'BC0SSA34Z00'     |'D1710_SMAXB'| 'DIODE SMD SSA34-M3/61T(40V,3A)'           | 'SIL'   | 'SSA34-M3/61T'    | 'EP(V1)'     | ''        | 'IC'  | ''      | 'SSA34-M361T.msg' | 'F0T-PETER'      | 'SIL_SSA34-M361T.pdf'                 | ''            | ''  | ''         | ''      | '20221209' | ''    
 'SSA34-M3/61T'    | 'SMLF'    | 'EMPTY'  | 'BC0SSA34Z00'(!)  = ''              | ''             | 'BC0SSA34Z00'     |'D1710_SMAXB'| 'DIODE SMD SSA34-M3/61T(40V,3A)'           | 'SIL'   | 'SSA34-M3/61T'    | 'EP(V1)'     | ''        | 'IC'  | ''      | 'SSA34-M361T.msg' | 'F0T-PETER'      | 'SIL_SSA34-M361T.pdf'                 | ''            | ''  | ''         | ''      | '20221209' | ''    
 'BAS70WS'         | 'SMLF'    | 'IC'     | 'BCAS70WSZ00'(!)  = ''              | ''             | 'BCAS70WSZ00'     |'SOD323_1-85X1-25'| 'DIODE SCHOTTKY BAS70WS(70V,4A)'           | 'PJT'   | 'BAS70WS'         | 'EP(V1)'     | 'EP(V1)'  | 'IC'  | ''      | 'BAS70WS.msg'     | 'S7M-JAY'        | 'PJT_BAS70WS.pdf'                     | ''            | ''  | ''         | ''      | '20230109' | ''    
 'BAS70WS'         | 'SMLF'    | 'EMPTY'  | 'BCAS70WSZ00'(!)  = ''              | ''             | 'BCAS70WSZ00'     |'SOD323_1-85X1-25'| 'DIODE SCHOTTKY BAS70WS(70V,4A)'           | 'PJT'   | 'BAS70WS'         | 'EP(V1)'     | 'EP(V1)'  | 'IC'  | ''      | 'BAS70WS.msg'     | 'S7M-JAY'        | 'PJT_BAS70WS.pdf'                     | ''            | ''  | ''         | ''      | '20230109' | ''    
 'SD101BWS-TP'     | 'SMLF'    | 'IC'     | 'BC101BWSZ00'(!)  = ''              | ''             | 'BC101BWSZ00'     |'SOD323XJ'| 'DIODE SMD SD101BWS-TP(50V,400MW)'         | 'MCE'   | 'SD101BWS-TP'     | 'EU(V1)'     | 'EU(V1)'  | 'IC'  | ''      | ''                | 'T2HV-EASON'     | 'MCE_SD101BWS-TP.pdf'                 | ''            | ''  | ''         | ''      | '20230110' | ''    
 'SD101BWS-TP'     | 'SMLF'    | 'EMPTY'  | 'BC101BWSZ00'(!)  = ''              | ''             | 'BC101BWSZ00'     |'SOD323XJ'| 'DIODE SMD SD101BWS-TP(50V,400MW)'         | 'MCE'   | 'SD101BWS-TP'     | 'EU(V1)'     | 'EU(V1)'  | 'IC'  | ''      | ''                | 'T2HV-EASON'     | 'MCE_SD101BWS-TP.pdf'                 | ''            | ''  | ''         | ''      | '20230110' | ''    
 'SS1030'          | 'SMLF'    | 'IC'     | 'BC001030Z02'(!)  = ''              | ''             | 'BC001030Z02'     |'SOD123XD'| 'DIODE SMD SS1030(30V,1A)SOD-123'          | 'PJT'   | 'SS1030'          | 'EP(V1)'     | 'EP(V1)'  | 'IC'  | ''      | ''                | 'S8G-KEN'        | 'PJT_SS1030.pdf'                      | ''            | ''  | ''         | ''      | '20230310' | ''    
 'SS1030'          | 'SMLF'    | 'EMPTY'  | 'BC001030Z02'(!)  = ''              | ''             | 'BC001030Z02'     |'SOD123XD'| 'DIODE SMD SS1030(30V,1A)SOD-123'          | 'PJT'   | 'SS1030'          | 'EP(V1)'     | 'EP(V1)'  | 'IC'  | ''      | ''                | 'S8G-KEN'        | 'PJT_SS1030.pdf'                      | ''            | ''  | ''         | ''      | '20230310' | ''    
 'CUS10F40'        | 'SMLF'    | 'IC'     | 'BCS10F40Z00'(!)  = ''              | ''             | 'BCS10F40Z00'     |'SOD323_1-7X1-25XB'| 'DIODE SMD CUS10F40(40V,1A,SCHOTTKY)'      | 'TOS'   | 'CUS10F40'        | 'EP(V1)'     | ''        | 'IC'  | ''      | ''                | 'A7M-ROD'        | 'TOS_CUS10F40.pdf'                    | ''            | ''  | ''         | ''      | '20230626' | ''    
 'CUS10F40'        | 'SMLF'    | 'EMPTY'  | 'BCS10F40Z00'(!)  = ''              | ''             | 'BCS10F40Z00'     |'SOD323_1-7X1-25XB'| 'DIODE SMD CUS10F40(40V,1A,SCHOTTKY)'      | 'TOS'   | 'CUS10F40'        | 'EP(V1)'     | ''        | 'IC'  | ''      | ''                | 'A7M-ROD'        | 'TOS_CUS10F40.pdf'                    | ''            | ''  | ''         | ''      | '20230626' | ''    
 'B340A-13-F'      | 'SMLF'    | 'IC'     | 'BC000340Z30SEL1'(!) = ''              | ''               | 'BC000340Z30SEL1' |'D2010XF'| 'DIODE SMD B340A-13-F(40V,3A)SCHOTTKYSELA' | 'DDS'   | 'B340A-13-F'      | 'EP(V1)'     | 'EP(V1)'  | 'IC'  | ''      | 'SEL_15QPN.xlsx'  | 'S5B-ROSSI'      | 'DDS_B340A-13-F.pdf'                  | ''            | ''  | ''         | ''      | '20230705' | ''    
 'B340A-13-F'      | 'SMLF'    | 'EMPTY'  | 'BC000340Z30SEL1'(!) = ''              | ''               | 'BC000340Z30SEL1' |'D2010XF'| 'DIODE SMD B340A-13-F(40V,3A)SCHOTTKYSELA' | 'DDS'   | 'B340A-13-F'      | 'EP(V1)'     | 'EP(V1)'  | 'IC'  | ''      | 'SEL_15QPN.xlsx'  | 'S5B-ROSSI'      | 'DDS_B340A-13-F.pdf'                  | ''            | ''  | ''         | ''      | '20230705' | ''    
 'MBRS540T3G'      | 'SMLF'    | 'IC'     | 'BC000540Z02SEL1'(!) = ''               | ''               | 'BC000540Z02SEL1' |'D2723_SMCXJ'| 'DIODE SCHOTTKY MBRS540T3G(40V5A,SMC)SELA' | 'ONS'   | 'MBRS540T3G'      | 'EP'         | 'EP'      | 'IC'  | ''      | 'SEL_15QPN.xlsx'  | 'S8A-JAY'        | 'ONS_MBRS540T3G.pdf'                  | ''            | ''  | ''         | ''      | '20230705' | ''    
 'MBRS540T3G'      | 'SMLF'    | 'EMPTY'  | 'BC000540Z02SEL1'(!) = ''               | ''               | 'BC000540Z02SEL1' |'D2723_SMCXJ'| 'DIODE SCHOTTKY MBRS540T3G(40V5A,SMC)SELA' | 'ONS'   | 'MBRS540T3G'      | 'EP'         | 'EP'      | 'IC'  | ''      | 'SEL_15QPN.xlsx'  | 'S8A-JAY'        | 'ONS_MBRS540T3G.pdf'                  | ''            | ''  | ''         | ''      | '20230705' | ''    
 'B380-13-F'       | 'SMLF'    | 'IC'     | 'BC00B380Z00SEL1'(!) = ''              | ''               | 'BC00B380Z00SEL1' |'D2723_SMCXD'| 'DIODE SMD B380-13(80V,100A,SCHOTTKY)SELA' | 'DDS'   | 'B380-13-F'       | 'EP(V1)'     | ''        | 'IC'  | ''      | 'SEL_15QPN.xlsx'  | 'T2L-CHEESE'     | 'DDS_B370-B3100.pdf'                  | ''            | ''  | ''         | ''      | '20230705' | ''    
 'B380-13-F'       | 'SMLF'    | 'EMPTY'  | 'BC00B380Z00SEL1'(!) = ''              | ''               | 'BC00B380Z00SEL1' |'D2723_SMCXD'| 'DIODE SMD B380-13(80V,100A,SCHOTTKY)SELA' | 'DDS'   | 'B380-13-F'       | 'EP(V1)'     | ''        | 'IC'  | ''      | 'SEL_15QPN.xlsx'  | 'T2L-CHEESE'     | 'DDS_B370-B3100.pdf'                  | ''            | ''  | ''         | ''      | '20230705' | ''    
 'MBR1H100SFT3G'   | 'SMLF'    | 'IC'     | 'BC01H100000SEL1'(!) = ''              | ''               | 'BC01H100000SEL1' |'SOD123_2-7X1-65'| 'DIODE SMD MBR1H100SFT3G(100V,1A)SELASN'   | 'ONS'   | 'MBR1H100SFT3G'   | 'EP(V1)'     | 'EP(V1)'  | 'IC'  | ''      | 'SEL_15QPN.xlsx'  | 'S8A-YC'         | 'ONS_MBR1H100SFT3G.pdf'               | ''            | ''  | ''         | ''      | '20230705' | ''    
 'MBR1H100SFT3G'   | 'SMLF'    | 'EMPTY'  | 'BC01H100000SEL1'(!) = ''              | ''               | 'BC01H100000SEL1' |'SOD123_2-7X1-65'| 'DIODE SMD MBR1H100SFT3G(100V,1A)SELASN'   | 'ONS'   | 'MBR1H100SFT3G'   | 'EP(V1)'     | 'EP(V1)'  | 'IC'  | ''      | 'SEL_15QPN.xlsx'  | 'S8A-YC'         | 'ONS_MBR1H100SFT3G.pdf'               | ''            | ''  | ''         | ''      | '20230705' | ''    
 '60V/51.70A'      | 'SMLF'    | 'IC'     | 'BC0MDJ60Z00SEL1'(!) = ''               | ''               | 'BC0MDJ60Z00SEL1' |'D2723_SMCXC'| 'DIODE SMD 5.0SMDJ60A(60V,51.70A)SELASN'   | 'LFI'   | '5.0SMDJ60A'      | 'EP(V1)'     | 'EP(V1)'  | 'IC'  | ''      | 'SEL_15QPN.xlsx'  | 'T2L-CHEESE'     | '5-0SMD SERIES.pdf'                   | ''            | ''  | ''         | ''      | '20230705' | ''    
 '60V/51.70A'      | 'SMLF'    | 'EMPTY'  | 'BC0MDJ60Z00SEL1'(!) = ''               | ''               | 'BC0MDJ60Z00SEL1' |'D2723_SMCXC'| 'DIODE SMD 5.0SMDJ60A(60V,51.70A)SELASN'   | 'LFI'   | '5.0SMDJ60A'      | 'EP(V1)'     | 'EP(V1)'  | 'IC'  | ''      | 'SEL_15QPN.xlsx'  | 'T2L-CHEESE'     | '5-0SMD SERIES.pdf'                   | ''            | ''  | ''         | ''      | '20230705' | ''    
 'PMEG1020EA'      | 'SMLF'    | 'IC'     | 'BC1020EAZ00SEL1'(!) = ''               | ''               | 'BC1020EAZ00SEL1' |'SOD323F_H44'| 'DIODE SMD PMEG1020EA(10V,2A)AECSELASN'    | 'NXP'   | 'PMEG1020EA'      | 'EU(V1)'     | ''        | 'IC'  | ''      | 'SEL_15QPN.xlsx'  | 'S8I-FRANK'      | 'NXP_PMEG1020EA.pdf'                  | ''            | ''  | ''         | ''      | '20230705' | ''    
 'PMEG1020EA'      | 'SMLF'    | 'EMPTY'  | 'BC1020EAZ00SEL1'(!) = ''               | ''               | 'BC1020EAZ00SEL1' |'SOD323F_H44'| 'DIODE SMD PMEG1020EA(10V,2A)AECSELASN'    | 'NXP'   | 'PMEG1020EA'      | 'EU(V1)'     | ''        | 'IC'  | ''      | 'SEL_15QPN.xlsx'  | 'S8I-FRANK'      | 'NXP_PMEG1020EA.pdf'                  | ''            | ''  | ''         | ''      | '20230705' | ''    

END_PART

END.

